# S9S_MB_2U (Grand Teton) — schematic netlist excerpt (pin names and nets, part order shuffled) for the footprints in the layout excerpt that follows; sources: Cadence DE-HDL packaged netlist, KiCad conversion of 03242023_DA0F0TMBIJ0_F0T_Motherboard_J_brd_V01_OCP.brd

C385  Q_CAP  47UF 4V 20% X6S  pkg C0805  page 75 : A = PVCCIN_CPU0 ; B = GND
R2562  Q_RES  0 5% CHIP  pkg 0402LF  page 206 : A = OCP_SFF_CLK_OE_N ; B = FM_DB2000_10_OE_N
R1474  Q_RES  1K 1% CHIP  pkg 0402LF  page 220 : A = FM_RST_PERST_BIT2 ; B = P3V3_AUX

(kicad_pcb
	(version 20260206)
	(generator "pcbnew")
	(generator_version "10.0")
	(general
		(thickness 1.6)
		(legacy_teardrops no)
	)
	(paper "A4")
	(title_block
		(title "03242023_DA0F0TMBIJ0_F0T_Motherboard_J_brd_V01_OCP.brd")
		(comment 1 "Grand Teton / footprints 4585-4587 of 6105")
	)
	(layers
		(0 "F.Cu" signal "TOP")
		(4 "In1.Cu" signal "GND")
		(6 "In2.Cu" signal "IN1")
		(8 "In3.Cu" signal "GND1")
		(10 "In4.Cu" signal "IN2")
		(12 "In5.Cu" signal "GND2")
		(14 "In6.Cu" signal "IN3")
		(16 "In7.Cu" signal "GND3")
		(18 "In8.Cu" signal "VCC")
		(20 "In9.Cu" signal "VCC1")
		(22 "In10.Cu" signal "GND4")
		(24 "In11.Cu" signal "IN4")
		(26 "In12.Cu" signal "GND5")
		(28 "In13.Cu" signal "IN5")
		(30 "In14.Cu" signal "GND6")
		(32 "In15.Cu" signal "IN6")
		(34 "In16.Cu" signal "GND7")
		(2 "B.Cu" signal "BOTTOM")
		(9 "F.Adhes" user "F.Adhesive")
		(11 "B.Adhes" user "B.Adhesive")
		(13 "F.Paste" user "Package Geometry/Pastemask Top")
		(15 "B.Paste" user "Package Geometry/Pastemask Bottom")
		(5 "F.SilkS" user "Ref Des/Silkscreen Top")
		(7 "B.SilkS" user "Ref Des/Silkscreen Bottom")
		(1 "F.Mask" user "Board Geometry/Soldermask Top")
		(3 "B.Mask" user "Board Geometry/Soldermask Bottom")
		(17 "Dwgs.User" user "User.Drawings")
		(19 "Cmts.User" user "User.Comments")
		(21 "Eco1.User" user "User.Eco1")
		(23 "Eco2.User" user "User.Eco2")
		(25 "Edge.Cuts" user "Board Geometry/Outline")
		(27 "Margin" user)
		(31 "F.CrtYd" user "Package Geometry/Place Bound Top")
		(29 "B.CrtYd" user "Package Geometry/Place Bound Bottom")
		(35 "F.Fab" user "Ref Des/Assembly Top")
		(33 "B.Fab" user "Ref Des/Assembly Bottom")
	)
	(footprint ""
		(layer "B.Cu")
		(at 229.89032 -127.029718 180)
		(property "Reference" "R2562"
			(at 0 0 0)
			(layer "B.SilkS")
			(hide yes)
			(effects
				(font
					(size 1.27 1.27)
				)
				(justify mirror)
			)
		)
		(property "Value" ""
			(at 0 0 0)
			(layer "B.Fab")
			(effects
				(font
					(size 1.27 1.27)
				)
				(justify mirror)
			)
		)
		(duplicate_pad_numbers_are_jumpers no)
		(fp_line
			(start 0.7874 0.4064)
			(end 0.7874 -0.4064)
			(stroke
				(width 0.1524)
				(type default)
			)
			(layer "B.SilkS")
		)
		(fp_line
			(start 0.7874 -0.4064)
			(end -0.7874 -0.4064)
			(stroke
				(width 0.1524)
				(type default)
			)
			(layer "B.SilkS")
		)
		(fp_line
			(start -0.7874 0.4064)
			(end 0.7874 0.4064)
			(stroke
				(width 0.1524)
				(type default)
			)
			(layer "B.SilkS")
		)
		(fp_line
			(start -0.7874 -0.4064)
			(end -0.7874 0.4064)
			(stroke
				(width 0.1524)
				(type default)
			)
			(layer "B.SilkS")
		)
		(fp_line
			(start 0.67945 0.3048)
			(end 0.67945 -0.305054)
			(stroke
				(width 0.1)
				(type default)
			)
			(layer "B.Fab")
		)
		(fp_line
			(start 0.67945 -0.305054)
			(end 0.12065 -0.305054)
			(stroke
				(width 0.1)
				(type default)
			)
			(layer "B.Fab")
		)
		(fp_line
			(start 0.12065 0.3048)
			(end 0.67945 0.3048)
			(stroke
				(width 0.1)
				(type default)
			)
			(layer "B.Fab")
		)
		(fp_line
			(start 0.12065 0.2794)
			(end 0.12065 0.3048)
			(stroke
				(width 0.1)
				(type default)
			)
			(layer "B.Fab")
		)
		(fp_line
			(start 0.12065 -0.2794)
			(end -0.12065 -0.2794)
			(stroke
				(width 0.1)
				(type default)
			)
			(layer "B.Fab")
		)
		(fp_line
			(start 0.12065 -0.305054)
			(end 0.12065 -0.2794)
			(stroke
				(width 0.1)
				(type default)
			)
			(layer "B.Fab")
		)
		(fp_line
			(start -0.120396 0.3048)
			(end -0.120396 0.2794)
			(stroke
				(width 0.1)
				(type default)
			)
			(layer "B.Fab")
		)
		(fp_line
			(start -0.120396 0.2794)
			(end 0.12065 0.2794)
			(stroke
				(width 0.1)
				(type default)
			)
			(layer "B.Fab")
		)
		(fp_line
			(start -0.12065 -0.2794)
			(end -0.12065 -0.3048)
			(stroke
				(width 0.1)
				(type default)
			)
			(layer "B.Fab")
		)
		(fp_line
			(start -0.12065 -0.3048)
			(end -0.67945 -0.3048)
			(stroke
				(width 0.1)
				(type default)
			)
			(layer "B.Fab")
		)
		(fp_line
			(start -0.67945 0.3048)
			(end -0.120396 0.3048)
			(stroke
				(width 0.1)
				(type default)
			)
			(layer "B.Fab")
		)
		(fp_line
			(start -0.67945 -0.3048)
			(end -0.67945 0.3048)
			(stroke
				(width 0.1)
				(type default)
			)
			(layer "B.Fab")
		)
		(pad "1" smd circle
			(at 0.40005 0)
			(size 0 0)
			(layers "B.Cu" "B.Mask" "B.Paste")
			(net "OCP_SFF_CLK_OE_N")
		)
		(pad "2" smd circle
			(at -0.40005 0)
			(size 0 0)
			(layers "B.Cu" "B.Mask" "B.Paste")
			(net "FM_DB2000_10_OE_N")
		)
	)
	(footprint ""
		(layer "B.Cu")
		(at 193.60388 -104.955848 180)
		(property "Reference" "R1474"
			(at 0 0 0)
			(layer "B.SilkS")
			(hide yes)
			(effects
				(font
					(size 1.27 1.27)
				)
				(justify mirror)
			)
		)
		(property "Value" ""
			(at 0 0 0)
			(layer "B.Fab")
			(effects
				(font
					(size 1.27 1.27)
				)
				(justify mirror)
			)
		)
		(duplicate_pad_numbers_are_jumpers no)
		(fp_line
			(start 0.7874 0.4064)
			(end 0.7874 -0.4064)
			(stroke
				(width 0.1524)
				(type default)
			)
			(layer "B.SilkS")
		)
		(fp_line
			(start 0.7874 -0.4064)
			(end -0.7874 -0.4064)
			(stroke
				(width 0.1524)
				(type default)
			)
			(layer "B.SilkS")
		)
		(fp_line
			(start -0.7874 0.4064)
			(end 0.7874 0.4064)
			(stroke
				(width 0.1524)
				(type default)
			)
			(layer "B.SilkS")
		)
		(fp_line
			(start -0.7874 -0.4064)
			(end -0.7874 0.4064)
			(stroke
				(width 0.1524)
				(type default)
			)
			(layer "B.SilkS")
		)
		(fp_line
			(start 0.67945 0.3048)
			(end 0.67945 -0.305054)
			(stroke
				(width 0.1)
				(type default)
			)
			(layer "B.Fab")
		)
		(fp_line
			(start 0.67945 -0.305054)
			(end 0.12065 -0.305054)
			(stroke
				(width 0.1)
				(type default)
			)
			(layer "B.Fab")
		)
		(fp_line
			(start 0.12065 0.3048)
			(end 0.67945 0.3048)
			(stroke
				(width 0.1)
				(type default)
			)
			(layer "B.Fab")
		)
		(fp_line
			(start 0.12065 0.2794)
			(end 0.12065 0.3048)
			(stroke
				(width 0.1)
				(type default)
			)
			(layer "B.Fab")
		)
		(fp_line
			(start 0.12065 -0.2794)
			(end -0.12065 -0.2794)
			(stroke
				(width 0.1)
				(type default)
			)
			(layer "B.Fab")
		)
		(fp_line
			(start 0.12065 -0.305054)
			(end 0.12065 -0.2794)
			(stroke
				(width 0.1)
				(type default)
			)
			(layer "B.Fab")
		)
		(fp_line
			(start -0.120396 0.3048)
			(end -0.120396 0.2794)
			(stroke
				(width 0.1)
				(type default)
			)
			(layer "B.Fab")
		)
		(fp_line
			(start -0.120396 0.2794)
			(end 0.12065 0.2794)
			(stroke
				(width 0.1)
				(type default)
			)
			(layer "B.Fab")
		)
		(fp_line
			(start -0.12065 -0.2794)
			(end -0.12065 -0.3048)
			(stroke
				(width 0.1)
				(type default)
			)
			(layer "B.Fab")
		)
		(fp_line
			(start -0.12065 -0.3048)
			(end -0.67945 -0.3048)
			(stroke
				(width 0.1)
				(type default)
			)
			(layer "B.Fab")
		)
		(fp_line
			(start -0.67945 0.3048)
			(end -0.120396 0.3048)
			(stroke
				(width 0.1)
				(type default)
			)
			(layer "B.Fab")
		)
		(fp_line
			(start -0.67945 -0.3048)
			(end -0.67945 0.3048)
			(stroke
				(width 0.1)
				(type default)
			)
			(layer "B.Fab")
		)
		(pad "1" smd circle
			(at 0.40005 0)
			(size 0 0)
			(layers "B.Cu" "B.Mask" "B.Paste")
			(net "FM_RST_PERST_BIT2")
		)
		(pad "2" smd circle
			(at -0.40005 0)
			(size 0 0)
			(layers "B.Cu" "B.Mask" "B.Paste")
			(net "P3V3_AUX")
		)
	)
	(footprint ""
		(layer "B.Cu")
		(at 367.898934 -244.820186 -90)
		(property "Reference" "C385"
			(at 0 0 90)
			(layer "B.SilkS")
			(hide yes)
			(effects
				(font
					(size 1.27 1.27)
				)
				(justify mirror)
			)
		)
		(property "Value" ""
			(at 0 0 90)
			(layer "B.Fab")
			(effects
				(font
					(size 1.27 1.27)
				)
				(justify mirror)
			)
		)
		(duplicate_pad_numbers_are_jumpers no)
		(fp_line
			(start -1.524 0.762)
			(end 1.524 0.762)
			(stroke
				(width 0.1524)
				(type default)
			)
			(layer "B.SilkS")
		)
		(fp_line
			(start 1.524 0.762)
			(end 1.524 -0.762)
			(stroke
				(width 0.1524)
				(type default)
			)
			(layer "B.SilkS")
		)
		(fp_line
			(start -1.524 -0.762)
			(end -1.524 0.762)
			(stroke
				(width 0.1524)
				(type default)
			)
			(layer "B.SilkS")
		)
		(fp_line
			(start 1.524 -0.762)
			(end -1.524 -0.762)
			(stroke
				(width 0.1524)
				(type default)
			)
			(layer "B.SilkS")
		)
		(fp_line
			(start -1.1049 0.724916)
			(end -1.1049 -0.724916)
			(stroke
				(width 0.1)
				(type default)
			)
			(layer "B.Fab")
		)
		(fp_line
			(start 1.1049 0.724916)
			(end -1.1049 0.724916)
			(stroke
				(width 0.1)
				(type default)
			)
			(layer "B.Fab")
		)
		(fp_line
			(start -1.1049 -0.724916)
			(end 1.1049 -0.724916)
			(stroke
				(width 0.1)
				(type default)
			)
			(layer "B.Fab")
		)
		(fp_line
			(start 1.1049 -0.724916)
			(end 1.1049 0.724916)
			(stroke
				(width 0.1)
				(type default)
			)
			(layer "B.Fab")
		)
		(pad "1" smd rect
			(at 0.889 0 270)
			(size 1.016 1.27)
			(layers "B.Cu" "B.Mask" "B.Paste")
			(net "PVCCIN_CPU0")
		)
		(pad "2" smd rect
			(at -0.889 0 270)
			(size 1.016 1.27)
			(layers "B.Cu" "B.Mask" "B.Paste")
			(net "GND")
		)
	)
)
